(kicad_pcb
	(version 20260206)
	(generator "pcbnew")
	(generator_version "10.0")
	(general
		(thickness 1.6)
		(legacy_teardrops no)
	)
	(paper "A4")
	(title_block
		(title "Bryce Canyon_IOM_M2_16342-2_OCP.brd")
		(comment 1 "Bryce Canyon / footprints 719-726 of 1146")
	)
	(layers
		(0 "F.Cu" signal "TOP")
		(4 "In1.Cu" signal "L2GND")
		(6 "In2.Cu" signal "L3")
		(8 "In3.Cu" signal "L4VCC")
		(10 "In4.Cu" signal "L5VCC")
		(12 "In5.Cu" signal "L6")
		(14 "In6.Cu" signal "L7GND")
		(2 "B.Cu" signal "BOTTOM")
		(9 "F.Adhes" user "F.Adhesive")
		(11 "B.Adhes" user "B.Adhesive")
		(13 "F.Paste" user "Package Geometry/Pastemask Top")
		(15 "B.Paste" user "Package Geometry/Pastemask Bottom")
		(5 "F.SilkS" user "Ref Des/Silkscreen Top")
		(7 "B.SilkS" user "Ref Des/Silkscreen Bottom")
		(1 "F.Mask" user "Board Geometry/Soldermask Top")
		(3 "B.Mask" user "Board Geometry/Soldermask Bottom")
		(17 "Dwgs.User" user "User.Drawings")
		(19 "Cmts.User" user "User.Comments")
		(21 "Eco1.User" user "User.Eco1")
		(23 "Eco2.User" user "User.Eco2")
		(25 "Edge.Cuts" user "Board Geometry/Outline")
		(27 "Margin" user)
		(31 "F.CrtYd" user "Package Geometry/Place Bound Top")
		(29 "B.CrtYd" user "Package Geometry/Place Bound Bottom")
		(35 "F.Fab" user "Ref Des/Assembly Top")
		(33 "B.Fab" user "Ref Des/Assembly Bottom")
	)
	(footprint ""
		(layer "B.Cu")
		(at 12.091924 -136.715246 90)
		(property "Reference" "R251"
			(at 0 0 90)
			(layer "B.SilkS")
			(hide yes)
			(effects
				(font
					(size 1.27 1.27)
				)
				(justify mirror)
			)
		)
		(property "Value" "120R2F-GP"
			(at -0.064008 -3.993896 90)
			(unlocked yes)
			(layer "B.Fab")
			(hide yes)
			(effects
				(font
					(size 1.016 1.016)
					(thickness 0.1524)
				)
				(justify mirror)
			)
		)
		(property "Device Type" "R402H16"
			(at -0.064008 -5.517896 90)
			(unlocked yes)
			(layer "B.Fab")
			(hide yes)
			(effects
				(font
					(size 1.016 1.016)
					(thickness 0.1524)
				)
				(justify mirror)
			)
		)
		(duplicate_pad_numbers_are_jumpers no)
		(fp_line
			(start 0.508 -0.9398)
			(end 0.508 0.9398)
			(stroke
				(width 0.1524)
				(type default)
			)
			(layer "B.SilkS")
		)
		(fp_line
			(start -0.508 -0.9398)
			(end 0.508 -0.9398)
			(stroke
				(width 0.1524)
				(type default)
			)
			(layer "B.SilkS")
		)
		(fp_rect
			(start 0.508 0.9398)
			(end -0.508 -0.9398)
			(stroke
				(width 0)
				(type default)
			)
			(fill no)
			(layer "B.CrtYd")
		)
		(fp_rect
			(start 0.508 0.9398)
			(end -0.508 -0.9398)
			(stroke
				(width 0)
				(type default)
			)
			(fill no)
			(layer "B.Fab")
		)
		(pad "1" smd custom
			(at 0 -0.4445 270)
			(size 0.1397 0.1397)
			(layers "B.Cu" "B.Mask" "B.Paste")
			(net "MEMA_8")
			(options
				(clearance outline)
				(anchor circle)
			)
			(primitives
				(gr_poly
					(pts
						(arc
							(start -0.1778 0.2794)
							(mid -0.249642 0.249642)
							(end -0.2794 0.1778)
						)
						(arc
							(start -0.2794 -0.1778)
							(mid -0.249642 -0.249642)
							(end -0.1778 -0.2794)
						)
						(arc
							(start 0.1778 -0.2794)
							(mid 0.249642 -0.249642)
							(end 0.2794 -0.1778)
						)
						(arc
							(start 0.2794 0.1778)
							(mid 0.249642 0.249642)
							(end 0.1778 0.2794)
						)
					)
					(width 0)
					(fill yes)
				)
			)
		)
		(pad "2" smd custom
			(at 0 0.4445 270)
			(size 0.1397 0.1397)
			(layers "B.Cu" "B.Mask" "B.Paste")
			(net "P1V2_STBY")
			(options
				(clearance outline)
				(anchor circle)
			)
			(primitives
				(gr_poly
					(pts
						(arc
							(start -0.1778 0.2794)
							(mid -0.249642 0.249642)
							(end -0.2794 0.1778)
						)
						(arc
							(start -0.2794 -0.1778)
							(mid -0.249642 -0.249642)
							(end -0.1778 -0.2794)
						)
						(arc
							(start 0.1778 -0.2794)
							(mid 0.249642 -0.249642)
							(end 0.2794 -0.1778)
						)
						(arc
							(start 0.2794 0.1778)
							(mid 0.249642 0.249642)
							(end 0.1778 0.2794)
						)
					)
					(width 0)
					(fill yes)
				)
			)
		)
	)
	(footprint ""
		(layer "B.Cu")
		(at 35.2298 -122.9106 90)
		(property "Reference" "R767"
			(at 0 0 90)
			(layer "B.SilkS")
			(hide yes)
			(effects
				(font
					(size 1.27 1.27)
				)
				(justify mirror)
			)
		)
		(property "Value" "0R2J-2-GP"
			(at -0.064008 -3.993896 90)
			(unlocked yes)
			(layer "B.Fab")
			(hide yes)
			(effects
				(font
					(size 1.016 1.016)
					(thickness 0.1524)
				)
				(justify mirror)
			)
		)
		(property "Device Type" "R402H16"
			(at -0.064008 -5.517896 90)
			(unlocked yes)
			(layer "B.Fab")
			(hide yes)
			(effects
				(font
					(size 1.016 1.016)
					(thickness 0.1524)
				)
				(justify mirror)
			)
		)
		(duplicate_pad_numbers_are_jumpers no)
		(fp_line
			(start 0.508 -0.9398)
			(end 0.508 0.9398)
			(stroke
				(width 0.1524)
				(type default)
			)
			(layer "B.SilkS")
		)
		(fp_line
			(start -0.508 -0.9398)
			(end 0.508 -0.9398)
			(stroke
				(width 0.1524)
				(type default)
			)
			(layer "B.SilkS")
		)
		(fp_rect
			(start 0.508 0.9398)
			(end -0.508 -0.9398)
			(stroke
				(width 0)
				(type default)
			)
			(fill no)
			(layer "B.CrtYd")
		)
		(fp_rect
			(start 0.508 0.9398)
			(end -0.508 -0.9398)
			(stroke
				(width 0)
				(type default)
			)
			(fill no)
			(layer "B.Fab")
		)
		(pad "1" smd custom
			(at 0 -0.4445 270)
			(size 0.1397 0.1397)
			(layers "B.Cu" "B.Mask" "B.Paste")
			(net "FLA_CS_0_R")
			(options
				(clearance outline)
				(anchor circle)
			)
			(primitives
				(gr_poly
					(pts
						(arc
							(start -0.1778 0.2794)
							(mid -0.249642 0.249642)
							(end -0.2794 0.1778)
						)
						(arc
							(start -0.2794 -0.1778)
							(mid -0.249642 -0.249642)
							(end -0.1778 -0.2794)
						)
						(arc
							(start 0.1778 -0.2794)
							(mid 0.249642 -0.249642)
							(end 0.2794 -0.1778)
						)
						(arc
							(start 0.2794 0.1778)
							(mid 0.249642 0.249642)
							(end 0.1778 0.2794)
						)
					)
					(width 0)
					(fill yes)
				)
			)
		)
		(pad "2" smd custom
			(at 0 0.4445 270)
			(size 0.1397 0.1397)
			(layers "B.Cu" "B.Mask" "B.Paste")
			(net "BMC_CPU_DIS")
			(options
				(clearance outline)
				(anchor circle)
			)
			(primitives
				(gr_poly
					(pts
						(arc
							(start -0.1778 0.2794)
							(mid -0.249642 0.249642)
							(end -0.2794 0.1778)
						)
						(arc
							(start -0.2794 -0.1778)
							(mid -0.249642 -0.249642)
							(end -0.1778 -0.2794)
						)
						(arc
							(start 0.1778 -0.2794)
							(mid 0.249642 -0.249642)
							(end 0.2794 -0.1778)
						)
						(arc
							(start 0.2794 0.1778)
							(mid 0.249642 0.249642)
							(end 0.1778 0.2794)
						)
					)
					(width 0)
					(fill yes)
				)
			)
		)
	)
	(footprint ""
		(layer "B.Cu")
		(at 52.2478 -162.1028 -90)
		(property "Reference" "R821"
			(at 0 0 90)
			(layer "B.SilkS")
			(hide yes)
			(effects
				(font
					(size 1.27 1.27)
				)
				(justify mirror)
			)
		)
		(property "Value" "1KR2F-3-GP"
			(at -0.064008 -3.993896 270)
			(unlocked yes)
			(layer "B.Fab")
			(hide yes)
			(effects
				(font
					(size 1.016 1.016)
					(thickness 0.1524)
				)
				(justify mirror)
			)
		)
		(property "Device Type" "R402H16"
			(at -0.064008 -5.517896 270)
			(unlocked yes)
			(layer "B.Fab")
			(hide yes)
			(effects
				(font
					(size 1.016 1.016)
					(thickness 0.1524)
				)
				(justify mirror)
			)
		)
		(duplicate_pad_numbers_are_jumpers no)
		(fp_line
			(start -0.508 -0.9398)
			(end 0.508 -0.9398)
			(stroke
				(width 0.1524)
				(type default)
			)
			(layer "B.SilkS")
		)
		(fp_line
			(start 0.508 -0.9398)
			(end 0.508 0.9398)
			(stroke
				(width 0.1524)
				(type default)
			)
			(layer "B.SilkS")
		)
		(fp_rect
			(start 0.508 0.9398)
			(end -0.508 -0.9398)
			(stroke
				(width 0)
				(type default)
			)
			(fill no)
			(layer "B.CrtYd")
		)
		(fp_rect
			(start 0.508 0.9398)
			(end -0.508 -0.9398)
			(stroke
				(width 0)
				(type default)
			)
			(fill no)
			(layer "B.Fab")
		)
		(pad "1" smd custom
			(at 0 -0.4445 90)
			(size 0.1397 0.1397)
			(layers "B.Cu" "B.Mask" "B.Paste")
			(net "ADC_P3V3_M2")
			(options
				(clearance outline)
				(anchor circle)
			)
			(primitives
				(gr_poly
					(pts
						(arc
							(start -0.1778 0.2794)
							(mid -0.249642 0.249642)
							(end -0.2794 0.1778)
						)
						(arc
							(start -0.2794 -0.1778)
							(mid -0.249642 -0.249642)
							(end -0.1778 -0.2794)
						)
						(arc
							(start 0.1778 -0.2794)
							(mid 0.249642 -0.249642)
							(end 0.2794 -0.1778)
						)
						(arc
							(start 0.2794 0.1778)
							(mid 0.249642 0.249642)
							(end 0.1778 0.2794)
						)
					)
					(width 0)
					(fill yes)
				)
			)
		)
		(pad "2" smd custom
			(at 0 0.4445 90)
			(size 0.1397 0.1397)
			(layers "B.Cu" "B.Mask" "B.Paste")
			(net "GND")
			(options
				(clearance outline)
				(anchor circle)
			)
			(primitives
				(gr_poly
					(pts
						(arc
							(start -0.1778 0.2794)
							(mid -0.249642 0.249642)
							(end -0.2794 0.1778)
						)
						(arc
							(start -0.2794 -0.1778)
							(mid -0.249642 -0.249642)
							(end -0.1778 -0.2794)
						)
						(arc
							(start 0.1778 -0.2794)
							(mid 0.249642 -0.249642)
							(end 0.2794 -0.1778)
						)
						(arc
							(start 0.2794 0.1778)
							(mid 0.249642 0.249642)
							(end 0.1778 0.2794)
						)
					)
					(width 0)
					(fill yes)
				)
			)
		)
	)
	(footprint ""
		(layer "B.Cu")
		(at 136.323324 -17.460468 -90)
		(property "Reference" "R742"
			(at 0 0 90)
			(layer "B.SilkS")
			(hide yes)
			(effects
				(font
					(size 1.27 1.27)
				)
				(justify mirror)
			)
		)
		(property "Value" "10KR2F-2-GP"
			(at -0.064008 -3.993896 270)
			(unlocked yes)
			(layer "B.Fab")
			(hide yes)
			(effects
				(font
					(size 1.016 1.016)
					(thickness 0.1524)
				)
				(justify mirror)
			)
		)
		(property "Device Type" "R402H16"
			(at -0.064008 -5.517896 270)
			(unlocked yes)
			(layer "B.Fab")
			(hide yes)
			(effects
				(font
					(size 1.016 1.016)
					(thickness 0.1524)
				)
				(justify mirror)
			)
		)
		(duplicate_pad_numbers_are_jumpers no)
		(fp_line
			(start -0.508 -0.9398)
			(end 0.508 -0.9398)
			(stroke
				(width 0.1524)
				(type default)
			)
			(layer "B.SilkS")
		)
		(fp_line
			(start 0.508 -0.9398)
			(end 0.508 0.9398)
			(stroke
				(width 0.1524)
				(type default)
			)
			(layer "B.SilkS")
		)
		(fp_rect
			(start 0.508 0.9398)
			(end -0.508 -0.9398)
			(stroke
				(width 0)
				(type default)
			)
			(fill no)
			(layer "B.CrtYd")
		)
		(fp_rect
			(start 0.508 0.9398)
			(end -0.508 -0.9398)
			(stroke
				(width 0)
				(type default)
			)
			(fill no)
			(layer "B.Fab")
		)
		(pad "1" smd custom
			(at 0 -0.4445 90)
			(size 0.1397 0.1397)
			(layers "B.Cu" "B.Mask" "B.Paste")
			(net "P12V_IOM")
			(options
				(clearance outline)
				(anchor circle)
			)
			(primitives
				(gr_poly
					(pts
						(arc
							(start -0.1778 0.2794)
							(mid -0.249642 0.249642)
							(end -0.2794 0.1778)
						)
						(arc
							(start -0.2794 -0.1778)
							(mid -0.249642 -0.249642)
							(end -0.1778 -0.2794)
						)
						(arc
							(start 0.1778 -0.2794)
							(mid 0.249642 -0.249642)
							(end 0.2794 -0.1778)
						)
						(arc
							(start 0.2794 0.1778)
							(mid 0.249642 0.249642)
							(end 0.1778 0.2794)
						)
					)
					(width 0)
					(fill yes)
				)
			)
		)
		(pad "2" smd custom
			(at 0 0.4445 90)
			(size 0.1397 0.1397)
			(layers "B.Cu" "B.Mask" "B.Paste")
			(net "IOM_MATED_N")
			(options
				(clearance outline)
				(anchor circle)
			)
			(primitives
				(gr_poly
					(pts
						(arc
							(start -0.1778 0.2794)
							(mid -0.249642 0.249642)
							(end -0.2794 0.1778)
						)
						(arc
							(start -0.2794 -0.1778)
							(mid -0.249642 -0.249642)
							(end -0.1778 -0.2794)
						)
						(arc
							(start 0.1778 -0.2794)
							(mid 0.249642 -0.249642)
							(end 0.2794 -0.1778)
						)
						(arc
							(start 0.2794 0.1778)
							(mid 0.249642 0.249642)
							(end 0.1778 0.2794)
						)
					)
					(width 0)
					(fill yes)
				)
			)
		)
	)
	(footprint ""
		(layer "B.Cu")
		(at 224.881186 -55.88381)
		(property "Reference" "L6"
			(at 0 0 0)
			(layer "B.SilkS")
			(hide yes)
			(effects
				(font
					(size 1.27 1.27)
				)
				(justify mirror)
			)
		)
		(property "Value" "BLM21PG220SN1DGP"
			(at -0.0254 -5.6896 0)
			(unlocked yes)
			(layer "B.Fab")
			(hide yes)
			(effects
				(font
					(size 1.016 1.016)
					(thickness 0.1524)
				)
				(justify mirror)
			)
		)
		(property "Device Type" "L20125H42"
			(at -0.0254 -7.5946 0)
			(unlocked yes)
			(layer "B.Fab")
			(hide yes)
			(effects
				(font
					(size 1.016 1.016)
					(thickness 0.1524)
				)
				(justify mirror)
			)
		)
		(duplicate_pad_numbers_are_jumpers no)
		(fp_line
			(start -0.9144 -1.7018)
			(end 0.9144 -1.7018)
			(stroke
				(width 0.1524)
				(type default)
			)
			(layer "B.SilkS")
		)
		(fp_line
			(start -0.9144 1.7018)
			(end -0.9144 -1.7018)
			(stroke
				(width 0.1524)
				(type default)
			)
			(layer "B.SilkS")
		)
		(fp_line
			(start 0.9144 -1.7018)
			(end 0.9144 1.7018)
			(stroke
				(width 0.1524)
				(type default)
			)
			(layer "B.SilkS")
		)
		(fp_line
			(start 0.9144 1.7018)
			(end -0.9144 1.7018)
			(stroke
				(width 0.1524)
				(type default)
			)
			(layer "B.SilkS")
		)
		(fp_rect
			(start 1.0033 1.778)
			(end -1.0033 -1.778)
			(stroke
				(width 0)
				(type default)
			)
			(fill no)
			(layer "B.CrtYd")
		)
		(fp_poly
			(pts
				(xy 1.0033 -1.778) (xy -1.0033 -1.778) (xy -1.0033 1.778) (xy 1.0033 1.778)
			)
			(stroke
				(width 0)
				(type default)
			)
			(fill no)
			(layer "B.Fab")
		)
		(pad "1" smd rect
			(at 0 -0.9652 180)
			(size 1.397 1.143)
			(layers "B.Cu" "B.Mask" "B.Paste")
			(net "P12V_STBY")
		)
		(pad "2" smd rect
			(at 0 0.9652 180)
			(size 1.397 1.143)
			(layers "B.Cu" "B.Mask" "B.Paste")
			(net "P12V_STBY_VIN_PU1")
		)
	)
	(footprint ""
		(layer "B.Cu")
		(at 35.007296 -139.330684 180)
		(property "Reference" "C106"
			(at 0 0 0)
			(layer "B.SilkS")
			(hide yes)
			(effects
				(font
					(size 1.27 1.27)
				)
				(justify mirror)
			)
		)
		(property "Value" "SC4D7U25V5KX-1-GP"
			(at 0.0762 -6.1214 180)
			(unlocked yes)
			(layer "B.Fab")
			(hide yes)
			(effects
				(font
					(size 1.016 1.016)
					(thickness 0.1524)
				)
				(justify mirror)
			)
		)
		(property "Device Type" "C805H58"
			(at 0.0762 -8.1534 180)
			(unlocked yes)
			(layer "B.Fab")
			(hide yes)
			(effects
				(font
					(size 1.016 1.016)
					(thickness 0.1524)
				)
				(justify mirror)
			)
		)
		(duplicate_pad_numbers_are_jumpers no)
		(fp_line
			(start -0.635 0)
			(end 0.635 0)
			(stroke
				(width 0.508)
				(type default)
			)
			(layer "B.SilkS")
		)
		(fp_rect
			(start 0.9652 1.778)
			(end -0.9652 -1.778)
			(stroke
				(width 0)
				(type default)
			)
			(fill no)
			(layer "B.CrtYd")
		)
		(fp_poly
			(pts
				(xy 0.9652 -1.778) (xy -0.9652 -1.778) (xy -0.9652 1.778) (xy 0.9652 1.778)
			)
			(stroke
				(width 0)
				(type default)
			)
			(fill no)
			(layer "B.Fab")
		)
		(pad "1" smd rect
			(at 0 -0.9652)
			(size 1.397 1.143)
			(layers "B.Cu" "B.Mask" "B.Paste")
			(net "P3V3_STBY")
		)
		(pad "2" smd rect
			(at 0 0.9652)
			(size 1.397 1.143)
			(layers "B.Cu" "B.Mask" "B.Paste")
			(net "GND")
		)
	)
	(footprint ""
		(layer "B.Cu")
		(at 178.458114 -122.988832 -90)
		(property "Reference" "R816"
			(at 0 0 90)
			(layer "B.SilkS")
			(hide yes)
			(effects
				(font
					(size 1.27 1.27)
				)
				(justify mirror)
			)
		)
		(property "Value" "1KR2F-3-GP"
			(at -0.064008 -3.993896 270)
			(unlocked yes)
			(layer "B.Fab")
			(hide yes)
			(effects
				(font
					(size 1.016 1.016)
					(thickness 0.1524)
				)
				(justify mirror)
			)
		)
		(property "Device Type" "R402H16"
			(at -0.064008 -5.517896 270)
			(unlocked yes)
			(layer "B.Fab")
			(hide yes)
			(effects
				(font
					(size 1.016 1.016)
					(thickness 0.1524)
				)
				(justify mirror)
			)
		)
		(duplicate_pad_numbers_are_jumpers no)
		(fp_line
			(start -0.508 -0.9398)
			(end 0.508 -0.9398)
			(stroke
				(width 0.1524)
				(type default)
			)
			(layer "B.SilkS")
		)
		(fp_line
			(start 0.508 -0.9398)
			(end 0.508 0.9398)
			(stroke
				(width 0.1524)
				(type default)
			)
			(layer "B.SilkS")
		)
		(fp_rect
			(start 0.508 0.9398)
			(end -0.508 -0.9398)
			(stroke
				(width 0)
				(type default)
			)
			(fill no)
			(layer "B.CrtYd")
		)
		(fp_rect
			(start 0.508 0.9398)
			(end -0.508 -0.9398)
			(stroke
				(width 0)
				(type default)
			)
			(fill no)
			(layer "B.Fab")
		)
		(pad "1" smd custom
			(at 0 -0.4445 90)
			(size 0.1397 0.1397)
			(layers "B.Cu" "B.Mask" "B.Paste")
			(net "P1V8_STBY")
			(options
				(clearance outline)
				(anchor circle)
			)
			(primitives
				(gr_poly
					(pts
						(arc
							(start -0.1778 0.2794)
							(mid -0.249642 0.249642)
							(end -0.2794 0.1778)
						)
						(arc
							(start -0.2794 -0.1778)
							(mid -0.249642 -0.249642)
							(end -0.1778 -0.2794)
						)
						(arc
							(start 0.1778 -0.2794)
							(mid 0.249642 -0.249642)
							(end 0.2794 -0.1778)
						)
						(arc
							(start 0.2794 0.1778)
							(mid 0.249642 0.249642)
							(end 0.1778 0.2794)
						)
					)
					(width 0)
					(fill yes)
				)
			)
		)
		(pad "2" smd custom
			(at 0 0.4445 90)
			(size 0.1397 0.1397)
			(layers "B.Cu" "B.Mask" "B.Paste")
			(net "I2C_M2_2_1V8_SDA")
			(options
				(clearance outline)
				(anchor circle)
			)
			(primitives
				(gr_poly
					(pts
						(arc
							(start -0.1778 0.2794)
							(mid -0.249642 0.249642)
							(end -0.2794 0.1778)
						)
						(arc
							(start -0.2794 -0.1778)
							(mid -0.249642 -0.249642)
							(end -0.1778 -0.2794)
						)
						(arc
							(start 0.1778 -0.2794)
							(mid 0.249642 -0.249642)
							(end 0.2794 -0.1778)
						)
						(arc
							(start 0.2794 0.1778)
							(mid 0.249642 0.249642)
							(end 0.1778 0.2794)
						)
					)
					(width 0)
					(fill yes)
				)
			)
		)
	)
	(footprint ""
		(layer "B.Cu")
		(at 79.008478 -50.209196 180)
		(property "Reference" "C28"
			(at 0 0 0)
			(layer "B.SilkS")
			(hide yes)
			(effects
				(font
					(size 1.27 1.27)
				)
				(justify mirror)
			)
		)
		(property "Value" "SC2D2U25V5KX-2-GP"
			(at 0.0762 -6.1214 180)
			(unlocked yes)
			(layer "B.Fab")
			(hide yes)
			(effects
				(font
					(size 1.016 1.016)
					(thickness 0.1524)
				)
				(justify mirror)
			)
		)
		(property "Device Type" "C805H54"
			(at 0.0762 -8.1534 180)
			(unlocked yes)
			(layer "B.Fab")
			(hide yes)
			(effects
				(font
					(size 1.016 1.016)
					(thickness 0.1524)
				)
				(justify mirror)
			)
		)
		(duplicate_pad_numbers_are_jumpers no)
		(fp_line
			(start -0.635 0)
			(end 0.635 0)
			(stroke
				(width 0.508)
				(type default)
			)
			(layer "B.SilkS")
		)
		(fp_rect
			(start 0.9652 1.778)
			(end -0.9652 -1.778)
			(stroke
				(width 0)
				(type default)
			)
			(fill no)
			(layer "B.CrtYd")
		)
		(fp_poly
			(pts
				(xy 0.9652 -1.778) (xy -0.9652 -1.778) (xy -0.9652 1.778) (xy 0.9652 1.778)
			)
			(stroke
				(width 0)
				(type default)
			)
			(fill no)
			(layer "B.Fab")
		)
		(pad "1" smd rect
			(at 0 -0.9652)
			(size 1.397 1.143)
			(layers "B.Cu" "B.Mask" "B.Paste")
			(net "P12V_STBY")
		)
		(pad "2" smd rect
			(at 0 0.9652)
			(size 1.397 1.143)
			(layers "B.Cu" "B.Mask" "B.Paste")
			(net "GND")
		)
	)
)
